(kicad_pcb
	(version 20260206)
	(generator "pcbnew")
	(generator_version "10.0")
	(general
		(thickness 1.6)
		(legacy_teardrops no)
	)
	(paper "A4")
	(title_block
		(title "v1-pdb — T6M_PDB_D_0927_0900.brd")
		(comment 1 "Open CloudServer (Microsoft) / footprint 239 of 321 (J26), pads 157-166 of 166")
	)
	(layers
		(0 "F.Cu" signal "TOP")
		(4 "In1.Cu" signal "GND")
		(6 "In2.Cu" signal "IN1")
		(8 "In3.Cu" signal "VCC")
		(10 "In4.Cu" signal "VCC1")
		(12 "In5.Cu" signal "IN2")
		(14 "In6.Cu" signal "GND1")
		(2 "B.Cu" signal "BOTTOM")
		(9 "F.Adhes" user "F.Adhesive")
		(11 "B.Adhes" user "B.Adhesive")
		(13 "F.Paste" user "Package Geometry/Pastemask Top")
		(15 "B.Paste" user "Package Geometry/Pastemask Bottom")
		(5 "F.SilkS" user "Ref Des/Silkscreen Top")
		(7 "B.SilkS" user "Ref Des/Silkscreen Bottom")
		(1 "F.Mask" user "Board Geometry/Soldermask Top")
		(3 "B.Mask" user "Board Geometry/Soldermask Bottom")
		(17 "Dwgs.User" user "User.Drawings")
		(19 "Cmts.User" user "User.Comments")
		(21 "Eco1.User" user "User.Eco1")
		(23 "Eco2.User" user "User.Eco2")
		(25 "Edge.Cuts" user "Board Geometry/Outline")
		(27 "Margin" user)
		(31 "F.CrtYd" user "Package Geometry/Place Bound Top")
		(29 "B.CrtYd" user "Package Geometry/Place Bound Bottom")
		(35 "F.Fab" user "Ref Des/Assembly Top")
		(33 "B.Fab" user "Ref Des/Assembly Bottom")
	)
	(footprint ""
		(layer "F.Cu")
		(at 6.448806 -261.670546)
		(property "Reference" "J26"
			(at 6.660642 8.995918 90)
			(unlocked yes)
			(layer "F.SilkS")
			(effects
				(font
					(size 0.7874 0.5842)
					(thickness 0.1524)
				)
				(justify left)
			)
		)
		(property "Value" ""
			(at 0 0 0)
			(layer "F.Fab")
			(effects
				(font
					(size 1.27 1.27)
				)
			)
		)
		(duplicate_pad_numbers_are_jumpers no)
		(pad "B73" thru_hole circle
			(at -2.499868 74.000106 270)
			(size 1.016 1.016)
			(drill 0.7112)
			(layers "*.Cu" "*.Mask")
			(remove_unused_layers no)
			(net "LAN1_P3_N")
			(clearance 0.1016)
			(thermal_gap 0.1016)
		)
		(pad "B74" thru_hole circle
			(at -4.499864 75.000104 270)
			(size 1.016 1.016)
			(drill 0.7112)
			(layers "*.Cu" "*.Mask")
			(remove_unused_layers no)
			(net "GND")
			(clearance 0.1016)
			(thermal_gap 0.1016)
		)
		(pad "B75" thru_hole circle
			(at -2.499868 76.000102 270)
			(size 1.016 1.016)
			(drill 0.7112)
			(layers "*.Cu" "*.Mask")
			(remove_unused_layers no)
			(net "LAN1_P4_P")
			(clearance 0.1016)
			(thermal_gap 0.1016)
		)
		(pad "B76" thru_hole circle
			(at -4.499864 77.0001 270)
			(size 1.016 1.016)
			(drill 0.7112)
			(layers "*.Cu" "*.Mask")
			(remove_unused_layers no)
			(net "LAN1_P4_N")
			(clearance 0.1016)
			(thermal_gap 0.1016)
		)
		(pad "B77" thru_hole circle
			(at -2.499868 78.000098 270)
			(size 1.016 1.016)
			(drill 0.7112)
			(layers "*.Cu" "*.Mask")
			(remove_unused_layers no)
			(net "GND")
			(clearance 0.1016)
			(thermal_gap 0.1016)
		)
		(pad "B78" thru_hole circle
			(at -4.499864 79.000096 270)
			(size 1.016 1.016)
			(drill 0.7112)
			(layers "*.Cu" "*.Mask")
			(remove_unused_layers no)
			(net "CM_PWR_CTL_IN")
			(clearance 0.1016)
			(thermal_gap 0.1016)
		)
		(pad "B79" thru_hole circle
			(at -2.499868 80.000094 270)
			(size 1.016 1.016)
			(drill 0.7112)
			(layers "*.Cu" "*.Mask")
			(remove_unused_layers no)
			(net "P12V")
			(clearance 0.1016)
			(thermal_gap 0.1016)
		)
		(pad "B80" thru_hole circle
			(at -4.499864 81.000092 270)
			(size 1.016 1.016)
			(drill 0.7112)
			(layers "*.Cu" "*.Mask")
			(remove_unused_layers no)
			(net "P12V")
			(clearance 0.1016)
			(thermal_gap 0.1016)
		)
		(pad "B81" thru_hole circle
			(at -2.499868 82.00009 270)
			(size 1.016 1.016)
			(drill 0.7112)
			(layers "*.Cu" "*.Mask")
			(remove_unused_layers no)
			(net "MATE_A1")
			(clearance 0.1016)
			(thermal_gap 0.1016)
		)
		(pad "B82" thru_hole circle
			(at -4.499864 83.000088 270)
			(size 1.016 1.016)
			(drill 0.7112)
			(layers "*.Cu" "*.Mask")
			(remove_unused_layers no)
			(net "P12V")
			(clearance 0.1016)
			(thermal_gap 0.1016)
		)
	)
)
